FILE_TYPE=LIBRARY_PARTS;
primitive 'SCONN8_G802M0083150RD3HR';
  pin
    '1':
      PIN_NUMBER='(1)';
      BIDIRECTIONAL='TRUE';
      INPUT_LOAD='(-0.01,0.01)';
      OUTPUT_LOAD='(1.0,-1.0)';
    '2':
      PIN_NUMBER='(2)';
      BIDIRECTIONAL='TRUE';
      INPUT_LOAD='(-0.01,0.01)';
      OUTPUT_LOAD='(1.0,-1.0)';
    '3':
      PIN_NUMBER='(3)';
      BIDIRECTIONAL='TRUE';
      INPUT_LOAD='(-0.01,0.01)';
      OUTPUT_LOAD='(1.0,-1.0)';
    '4':
      PIN_NUMBER='(4)';
      BIDIRECTIONAL='TRUE';
      INPUT_LOAD='(-0.01,0.01)';
      OUTPUT_LOAD='(1.0,-1.0)';
    '5':
      PIN_NUMBER='(5)';
      BIDIRECTIONAL='TRUE';
      INPUT_LOAD='(-0.01,0.01)';
      OUTPUT_LOAD='(1.0,-1.0)';
    '6':
      PIN_NUMBER='(6)';
      BIDIRECTIONAL='TRUE';
      INPUT_LOAD='(-0.01,0.01)';
      OUTPUT_LOAD='(1.0,-1.0)';
    '7':
      PIN_NUMBER='(7)';
      BIDIRECTIONAL='TRUE';
      INPUT_LOAD='(-0.01,0.01)';
      OUTPUT_LOAD='(1.0,-1.0)';
    '8':
      PIN_NUMBER='(8)';
      BIDIRECTIONAL='TRUE';
      INPUT_LOAD='(-0.01,0.01)';
      OUTPUT_LOAD='(1.0,-1.0)';
  end_pin;
  body
    PART_NAME='SCONN8_G802M0083150RD3HR';
    BODY_NAME='SCONN8_G802M0083150RD3HR';
    PHYS_DES_PREFIX='J';
    CLASS='IO';
  end_body;
end_primitive;

END.
